(kicad_pcb
	(version 20241229)
	(generator "pcbnew")
	(generator_version "9.0")
	(general
		(thickness 1.292)
		(legacy_teardrops no)
	)
	(paper "A4")
	(title_block
		(title "LPDDR5 Testbed")
		(date "2023-12-19")
		(rev "1.0.0")
		(comment 9 "footprints 1-7 of 160")
	)
	(layers
		(0 "F.Cu" signal)
		(4 "In1.Cu" power)
		(6 "In2.Cu" power)
		(8 "In3.Cu" signal)
		(10 "In4.Cu" signal)
		(2 "B.Cu" signal)
		(9 "F.Adhes" user "F.Adhesive")
		(11 "B.Adhes" user "B.Adhesive")
		(13 "F.Paste" user)
		(15 "B.Paste" user)
		(5 "F.SilkS" user "F.Silkscreen")
		(7 "B.SilkS" user "B.Silkscreen")
		(1 "F.Mask" user)
		(3 "B.Mask" user)
		(17 "Dwgs.User" user "User.Drawings")
		(19 "Cmts.User" user "User.Comments")
		(21 "Eco1.User" user "User.Eco1")
		(23 "Eco2.User" user "User.Eco2")
		(25 "Edge.Cuts" user)
		(27 "Margin" user)
		(31 "F.CrtYd" user "F.Courtyard")
		(29 "B.CrtYd" user "B.Courtyard")
		(35 "F.Fab" user)
		(33 "B.Fab" user)
	)
	(footprint "antmicro-footprints:TP_SMD_0.75mm"
		(layer "F.Cu")
		(at 160.8 69.5)
		(property "Reference" "TP8"
			(at -2.6 1.1 0)
			(unlocked yes)
			(layer "F.SilkS")
			(effects
				(font
					(size 0.7 0.7)
					(thickness 0.15)
				)
				(justify left bottom)
			)
		)
		(property "Value" "TP_0.75mm_SMD"
			(at 0 1.2 0)
			(layer "F.Fab")
			(effects
				(font
					(size 0.7 0.7)
					(thickness 0.15)
				)
				(justify left bottom)
			)
		)
		(property "Author" "Antmicro"
			(at 0 0 0)
			(layer "F.Fab")
			(hide yes)
			(effects
				(font
					(size 1 1)
					(thickness 0.15)
				)
			)
		)
		(property "License" "Apache-2.0"
			(at 0 0 0)
			(layer "F.Fab")
			(hide yes)
			(effects
				(font
					(size 1 1)
					(thickness 0.15)
				)
			)
		)
		(property "MPN" ""
			(at 0 0 0)
			(layer "F.Fab")
			(hide yes)
			(effects
				(font
					(size 1 1)
					(thickness 0.15)
				)
			)
		)
		(property "Manufacturer" ""
			(at 0 0 0)
			(layer "F.Fab")
			(hide yes)
			(effects
				(font
					(size 1 1)
					(thickness 0.15)
				)
			)
		)
		(sheetname "Power supply")
		(sheetfile "power_supply.kicad_sch")
		(attr exclude_from_pos_files)
		(pad "1" smd circle
			(at 0 0)
			(size 0.75 0.75)
			(layers "F.Cu" "F.Mask")
			(net 11 "/Power supply/VOUT")
			(pinfunction "1")
			(pintype "passive")
		)
	)
	(footprint "antmicro-footprints:R_Array_4x0402_Panasonic_EXB28V"
		(layer "F.Cu")
		(at 155.7 93.85)
		(property "Reference" "R63"
			(at -1.301 -1.45 0)
			(unlocked yes)
			(layer "F.SilkS")
			(effects
				(font
					(size 0.7 0.7)
					(thickness 0.15)
				)
				(justify left bottom)
			)
		)
		(property "Value" "R_4x100R_0402_array"
			(at -1.5 2 0)
			(layer "F.Fab")
			(effects
				(font
					(size 0.7 0.7)
					(thickness 0.15)
				)
				(justify left bottom)
			)
		)
		(property "Author" "Antmicro"
			(at 0 0 0)
			(layer "F.Fab")
			(hide yes)
			(effects
				(font
					(size 1 1)
					(thickness 0.15)
				)
			)
		)
		(property "License" "Apache-2.0"
			(at 0 0 0)
			(layer "F.Fab")
			(hide yes)
			(effects
				(font
					(size 1 1)
					(thickness 0.15)
				)
			)
		)
		(property "MPN" "EXB-28V101JX"
			(at 0 0 0)
			(layer "F.Fab")
			(hide yes)
			(effects
				(font
					(size 1 1)
					(thickness 0.15)
				)
			)
		)
		(property "Manufacturer" "Panasonic"
			(at 0 0 0)
			(layer "F.Fab")
			(hide yes)
			(effects
				(font
					(size 1 1)
					(thickness 0.15)
				)
			)
		)
		(property "Val" "R_4x100R_0402"
			(at 0 0 0)
			(layer "F.Fab")
			(hide yes)
			(effects
				(font
					(size 1 1)
					(thickness 0.15)
				)
			)
		)
		(sheetname "Translators1")
		(sheetfile "translators.kicad_sch")
		(attr smd)
		(fp_line
			(start -1.25 -0.5)
			(end -1.25 0.498)
			(stroke
				(width 0.15)
				(type solid)
			)
			(layer "F.SilkS")
		)
		(fp_line
			(start 1.25 0.499)
			(end 1.25 -0.499)
			(stroke
				(width 0.15)
				(type solid)
			)
			(layer "F.SilkS")
		)
		(fp_rect
			(start -1.25 -0.8)
			(end 1.25 0.8)
			(stroke
				(width 0.05)
				(type solid)
			)
			(fill no)
			(layer "F.CrtYd")
		)
		(fp_line
			(start -1 -0.5)
			(end 0.998 -0.5)
			(stroke
				(width 0.15)
				(type solid)
			)
			(layer "F.Fab")
		)
		(fp_line
			(start -1 0.498)
			(end -1 -0.5)
			(stroke
				(width 0.15)
				(type solid)
			)
			(layer "F.Fab")
		)
		(fp_line
			(start 0.998 -0.5)
			(end 0.998 0.498)
			(stroke
				(width 0.15)
				(type solid)
			)
			(layer "F.Fab")
		)
		(fp_line
			(start 0.998 0.498)
			(end -1 0.498)
			(stroke
				(width 0.15)
				(type solid)
			)
			(layer "F.Fab")
		)
		(pad "1" smd roundrect
			(at -0.8875 0.45)
			(size 0.525 0.5)
			(layers "F.Cu" "F.Mask" "F.Paste")
			(roundrect_rratio 0.25)
			(net 133 "/SODIMM/LPDDR5_IN_B.DQ15")
			(pinfunction "R1.1")
			(pintype "passive")
		)
		(pad "2" smd roundrect
			(at -0.25 0.45)
			(size 0.25 0.5)
			(layers "F.Cu" "F.Mask" "F.Paste")
			(roundrect_rratio 0.25)
			(net 134 "/SODIMM/LPDDR5_IN_B.DQ14")
			(pinfunction "R2.1")
			(pintype "passive")
		)
		(pad "3" smd roundrect
			(at 0.25 0.45)
			(size 0.25 0.5)
			(layers "F.Cu" "F.Mask" "F.Paste")
			(roundrect_rratio 0.25)
			(net 136 "/SODIMM/LPDDR5_IN_B.DQ12")
			(pinfunction "R3.1")
			(pintype "passive")
		)
		(pad "4" smd roundrect
			(at 0.8875 0.45)
			(size 0.525 0.5)
			(layers "F.Cu" "F.Mask" "F.Paste")
			(roundrect_rratio 0.25)
			(net 135 "/SODIMM/LPDDR5_IN_B.DQ13")
			(pinfunction "R4.1")
			(pintype "passive")
		)
		(pad "5" smd roundrect
			(at 0.8875 -0.45)
			(size 0.525 0.5)
			(layers "F.Cu" "F.Mask" "F.Paste")
			(roundrect_rratio 0.25)
			(net 214 "/LPDDR5/LPDDR5_B.DQ13")
			(pinfunction "R4.2")
			(pintype "passive")
		)
		(pad "6" smd roundrect
			(at 0.25 -0.45)
			(size 0.25 0.5)
			(layers "F.Cu" "F.Mask" "F.Paste")
			(roundrect_rratio 0.25)
			(net 213 "/LPDDR5/LPDDR5_B.DQ12")
			(pinfunction "R3.2")
			(pintype "passive")
		)
		(pad "7" smd roundrect
			(at -0.25 -0.45)
			(size 0.25 0.5)
			(layers "F.Cu" "F.Mask" "F.Paste")
			(roundrect_rratio 0.25)
			(net 215 "/LPDDR5/LPDDR5_B.DQ14")
			(pinfunction "R2.2")
			(pintype "passive")
		)
		(pad "8" smd roundrect
			(at -0.8875 -0.45)
			(size 0.525 0.5)
			(layers "F.Cu" "F.Mask" "F.Paste")
			(roundrect_rratio 0.25)
			(net 216 "/LPDDR5/LPDDR5_B.DQ15")
			(pinfunction "R1.2")
			(pintype "passive")
		)
	)
	(footprint "antmicro-footprints:C_0402_1005Metric"
		(layer "F.Cu")
		(at 144.225 81 -90)
		(descr "Capacitor SMD 0402")
		(tags "capacitor SMD 0402")
		(property "Reference" "C56"
			(at 1 -0.325 90)
			(unlocked yes)
			(layer "F.SilkS")
			(effects
				(font
					(size 0.7 0.7)
					(thickness 0.15)
				)
				(justify right bottom)
			)
		)
		(property "Value" "C_4u7_0402"
			(at -1.022927 2.155213 90)
			(layer "F.Fab")
			(effects
				(font
					(size 0.7 0.7)
					(thickness 0.15)
				)
				(justify right bottom)
			)
		)
		(property "Author" "Antmicro"
			(at 63.225 225.225 0)
			(layer "F.Fab")
			(hide yes)
			(effects
				(font
					(size 1 1)
					(thickness 0.15)
				)
			)
		)
		(property "Dielectric" ""
			(at 63.225 225.225 0)
			(layer "F.Fab")
			(hide yes)
			(effects
				(font
					(size 1 1)
					(thickness 0.15)
				)
			)
		)
		(property "License" "Apache-2.0"
			(at 63.225 225.225 0)
			(layer "F.Fab")
			(hide yes)
			(effects
				(font
					(size 1 1)
					(thickness 0.15)
				)
			)
		)
		(property "MPN" "GRM155R61A475MEAAD"
			(at 63.225 225.225 0)
			(layer "F.Fab")
			(hide yes)
			(effects
				(font
					(size 1 1)
					(thickness 0.15)
				)
			)
		)
		(property "Manufacturer" "Murata"
			(at 63.225 225.225 0)
			(layer "F.Fab")
			(hide yes)
			(effects
				(font
					(size 1 1)
					(thickness 0.15)
				)
			)
		)
		(property "Val" "4u7"
			(at 63.225 225.225 0)
			(layer "F.Fab")
			(hide yes)
			(effects
				(font
					(size 1 1)
					(thickness 0.15)
				)
			)
		)
		(property "Voltage" ""
			(at 63.225 225.225 0)
			(layer "F.Fab")
			(hide yes)
			(effects
				(font
					(size 1 1)
					(thickness 0.15)
				)
			)
		)
		(sheetname "LPDDR5")
		(sheetfile "lpddr5.kicad_sch")
		(attr smd)
		(fp_rect
			(start -0.9659 -0.481258)
			(end 0.9649 0.458742)
			(stroke
				(width 0.05)
				(type solid)
			)
			(fill no)
			(layer "F.CrtYd")
		)
		(fp_line
			(start -0.499 0.248)
			(end -0.499 -0.25)
			(stroke
				(width 0.15)
				(type solid)
			)
			(layer "F.Fab")
		)
		(fp_line
			(start 0.499 0.248)
			(end -0.499 0.248)
			(stroke
				(width 0.15)
				(type solid)
			)
			(layer "F.Fab")
		)
		(fp_line
			(start -0.499 -0.25)
			(end 0.499 -0.25)
			(stroke
				(width 0.15)
				(type solid)
			)
			(layer "F.Fab")
		)
		(fp_line
			(start 0.499 -0.25)
			(end 0.499 0.248)
			(stroke
				(width 0.15)
				(type solid)
			)
			(layer "F.Fab")
		)
		(pad "1" smd roundrect
			(at -0.484 0 270)
			(size 0.59 0.64)
			(layers "F.Cu" "F.Mask" "F.Paste")
			(roundrect_rratio 0.25)
			(net 14 "GND")
			(pintype "passive")
		)
		(pad "2" smd roundrect
			(at 0.484 0 270)
			(size 0.59 0.64)
			(layers "F.Cu" "F.Mask" "F.Paste")
			(roundrect_rratio 0.25)
			(net 12 "+0V9")
			(pintype "passive")
		)
	)
	(footprint "antmicro-footprints:TP_SMD_0.75mm"
		(layer "F.Cu")
		(at 103.6 62.95)
		(property "Reference" "TP4"
			(at -3.125 0.225 0)
			(unlocked yes)
			(layer "F.SilkS")
			(effects
				(font
					(size 0.7 0.7)
					(thickness 0.15)
				)
				(justify left bottom)
			)
		)
		(property "Value" "TP_0.75mm_SMD"
			(at 0 1.2 0)
			(layer "F.Fab")
			(effects
				(font
					(size 0.7 0.7)
					(thickness 0.15)
				)
				(justify left bottom)
			)
		)
		(property "Author" "Antmicro"
			(at 0 0 0)
			(layer "F.Fab")
			(hide yes)
			(effects
				(font
					(size 1 1)
					(thickness 0.15)
				)
			)
		)
		(property "License" "Apache-2.0"
			(at 0 0 0)
			(layer "F.Fab")
			(hide yes)
			(effects
				(font
					(size 1 1)
					(thickness 0.15)
				)
			)
		)
		(property "MPN" ""
			(at 0 0 0)
			(layer "F.Fab")
			(hide yes)
			(effects
				(font
					(size 1 1)
					(thickness 0.15)
				)
			)
		)
		(property "Manufacturer" ""
			(at 0 0 0)
			(layer "F.Fab")
			(hide yes)
			(effects
				(font
					(size 1 1)
					(thickness 0.15)
				)
			)
		)
		(sheetname "Power supply")
		(sheetfile "power_supply.kicad_sch")
		(attr exclude_from_pos_files)
		(pad "1" smd circle
			(at 0 0)
			(size 0.75 0.75)
			(layers "F.Cu" "F.Mask")
			(net 7 "/Power supply/VOUT1")
			(pinfunction "1")
			(pintype "passive")
		)
	)
	(footprint "antmicro-footprints:C_0402_1005Metric"
		(layer "F.Cu")
		(at 125.575 80.95 -90)
		(descr "Capacitor SMD 0402")
		(tags "capacitor SMD 0402")
		(property "Reference" "C59"
			(at 1.05 -0.325 90)
			(unlocked yes)
			(layer "F.SilkS")
			(effects
				(font
					(size 0.7 0.7)
					(thickness 0.15)
				)
				(justify right bottom)
			)
		)
		(property "Value" "C_4u7_0402"
			(at -1.022927 2.155213 90)
			(layer "F.Fab")
			(effects
				(font
					(size 0.7 0.7)
					(thickness 0.15)
				)
				(justify right bottom)
			)
		)
		(property "Author" "Antmicro"
			(at 44.625 206.525 0)
			(layer "F.Fab")
			(hide yes)
			(effects
				(font
					(size 1 1)
					(thickness 0.15)
				)
			)
		)
		(property "Dielectric" ""
			(at 44.625 206.525 0)
			(layer "F.Fab")
			(hide yes)
			(effects
				(font
					(size 1 1)
					(thickness 0.15)
				)
			)
		)
		(property "License" "Apache-2.0"
			(at 44.625 206.525 0)
			(layer "F.Fab")
			(hide yes)
			(effects
				(font
					(size 1 1)
					(thickness 0.15)
				)
			)
		)
		(property "MPN" "GRM155R61A475MEAAD"
			(at 44.625 206.525 0)
			(layer "F.Fab")
			(hide yes)
			(effects
				(font
					(size 1 1)
					(thickness 0.15)
				)
			)
		)
		(property "Manufacturer" "Murata"
			(at 44.625 206.525 0)
			(layer "F.Fab")
			(hide yes)
			(effects
				(font
					(size 1 1)
					(thickness 0.15)
				)
			)
		)
		(property "Val" "4u7"
			(at 44.625 206.525 0)
			(layer "F.Fab")
			(hide yes)
			(effects
				(font
					(size 1 1)
					(thickness 0.15)
				)
			)
		)
		(property "Voltage" ""
			(at 44.625 206.525 0)
			(layer "F.Fab")
			(hide yes)
			(effects
				(font
					(size 1 1)
					(thickness 0.15)
				)
			)
		)
		(sheetname "LPDDR5")
		(sheetfile "lpddr5.kicad_sch")
		(attr smd)
		(fp_rect
			(start -0.9659 -0.481258)
			(end 0.9649 0.458742)
			(stroke
				(width 0.05)
				(type solid)
			)
			(fill no)
			(layer "F.CrtYd")
		)
		(fp_line
			(start -0.499 0.248)
			(end -0.499 -0.25)
			(stroke
				(width 0.15)
				(type solid)
			)
			(layer "F.Fab")
		)
		(fp_line
			(start 0.499 0.248)
			(end -0.499 0.248)
			(stroke
				(width 0.15)
				(type solid)
			)
			(layer "F.Fab")
		)
		(fp_line
			(start -0.499 -0.25)
			(end 0.499 -0.25)
			(stroke
				(width 0.15)
				(type solid)
			)
			(layer "F.Fab")
		)
		(fp_line
			(start 0.499 -0.25)
			(end 0.499 0.248)
			(stroke
				(width 0.15)
				(type solid)
			)
			(layer "F.Fab")
		)
		(pad "1" smd roundrect
			(at -0.484 0 270)
			(size 0.59 0.64)
			(layers "F.Cu" "F.Mask" "F.Paste")
			(roundrect_rratio 0.25)
			(net 14 "GND")
			(pintype "passive")
		)
		(pad "2" smd roundrect
			(at 0.484 0 270)
			(size 0.59 0.64)
			(layers "F.Cu" "F.Mask" "F.Paste")
			(roundrect_rratio 0.25)
			(net 12 "+0V9")
			(pintype "passive")
		)
	)
	(footprint "antmicro-footprints:R_Array_4x0402_Panasonic_EXB28V"
		(layer "F.Cu")
		(at 130.3 93.8)
		(property "Reference" "R8"
			(at -0.7 -1.4 0)
			(unlocked yes)
			(layer "F.SilkS")
			(effects
				(font
					(size 0.7 0.7)
					(thickness 0.15)
				)
				(justify left bottom)
			)
		)
		(property "Value" "R_4x100R_0402_array"
			(at -1.5 2 0)
			(layer "F.Fab")
			(effects
				(font
					(size 0.7 0.7)
					(thickness 0.15)
				)
				(justify left bottom)
			)
		)
		(property "Author" "Antmicro"
			(at 0 0 0)
			(layer "F.Fab")
			(hide yes)
			(effects
				(font
					(size 1 1)
					(thickness 0.15)
				)
			)
		)
		(property "License" "Apache-2.0"
			(at 0 0 0)
			(layer "F.Fab")
			(hide yes)
			(effects
				(font
					(size 1 1)
					(thickness 0.15)
				)
			)
		)
		(property "MPN" "EXB-28V101JX"
			(at 0 0 0)
			(layer "F.Fab")
			(hide yes)
			(effects
				(font
					(size 1 1)
					(thickness 0.15)
				)
			)
		)
		(property "Manufacturer" "Panasonic"
			(at 0 0 0)
			(layer "F.Fab")
			(hide yes)
			(effects
				(font
					(size 1 1)
					(thickness 0.15)
				)
			)
		)
		(property "Val" "R_4x100R_0402"
			(at 0 0 0)
			(layer "F.Fab")
			(hide yes)
			(effects
				(font
					(size 1 1)
					(thickness 0.15)
				)
			)
		)
		(sheetname "Translators")
		(sheetfile "translators.kicad_sch")
		(attr smd)
		(fp_line
			(start -1.25 -0.5)
			(end -1.25 0.498)
			(stroke
				(width 0.15)
				(type solid)
			)
			(layer "F.SilkS")
		)
		(fp_line
			(start 1.25 0.499)
			(end 1.25 -0.499)
			(stroke
				(width 0.15)
				(type solid)
			)
			(layer "F.SilkS")
		)
		(fp_rect
			(start -1.25 -0.8)
			(end 1.25 0.8)
			(stroke
				(width 0.05)
				(type solid)
			)
			(fill no)
			(layer "F.CrtYd")
		)
		(fp_line
			(start -1 -0.5)
			(end 0.998 -0.5)
			(stroke
				(width 0.15)
				(type solid)
			)
			(layer "F.Fab")
		)
		(fp_line
			(start -1 0.498)
			(end -1 -0.5)
			(stroke
				(width 0.15)
				(type solid)
			)
			(layer "F.Fab")
		)
		(fp_line
			(start 0.998 -0.5)
			(end 0.998 0.498)
			(stroke
				(width 0.15)
				(type solid)
			)
			(layer "F.Fab")
		)
		(fp_line
			(start 0.998 0.498)
			(end -1 0.498)
			(stroke
				(width 0.15)
				(type solid)
			)
			(layer "F.Fab")
		)
		(pad "1" smd roundrect
			(at -0.8875 0.45)
			(size 0.525 0.5)
			(layers "F.Cu" "F.Mask" "F.Paste")
			(roundrect_rratio 0.25)
			(net 161 "/SODIMM/LPDDR5_IN_A.CA2")
			(pinfunction "R1.1")
			(pintype "passive")
		)
		(pad "2" smd roundrect
			(at -0.25 0.45)
			(size 0.25 0.5)
			(layers "F.Cu" "F.Mask" "F.Paste")
			(roundrect_rratio 0.25)
			(net 160 "/SODIMM/LPDDR5_IN_A.CA3")
			(pinfunction "R2.1")
			(pintype "passive")
		)
		(pad "3" smd roundrect
			(at 0.25 0.45)
			(size 0.25 0.5)
			(layers "F.Cu" "F.Mask" "F.Paste")
			(roundrect_rratio 0.25)
			(net 159 "/SODIMM/LPDDR5_IN_A.CA4")
			(pinfunction "R3.1")
			(pintype "passive")
		)
		(pad "4" smd roundrect
			(at 0.8875 0.45)
			(size 0.525 0.5)
			(layers "F.Cu" "F.Mask" "F.Paste")
			(roundrect_rratio 0.25)
			(net 158 "/SODIMM/LPDDR5_IN_A.CA5")
			(pinfunction "R4.1")
			(pintype "passive")
		)
		(pad "5" smd roundrect
			(at 0.8875 -0.45)
			(size 0.525 0.5)
			(layers "F.Cu" "F.Mask" "F.Paste")
			(roundrect_rratio 0.25)
			(net 56 "/LPDDR5/LPDDR5_A.CA5")
			(pinfunction "R4.2")
			(pintype "passive")
		)
		(pad "6" smd roundrect
			(at 0.25 -0.45)
			(size 0.25 0.5)
			(layers "F.Cu" "F.Mask" "F.Paste")
			(roundrect_rratio 0.25)
			(net 60 "/LPDDR5/LPDDR5_A.CA4")
			(pinfunction "R3.2")
			(pintype "passive")
		)
		(pad "7" smd roundrect
			(at -0.25 -0.45)
			(size 0.25 0.5)
			(layers "F.Cu" "F.Mask" "F.Paste")
			(roundrect_rratio 0.25)
			(net 54 "/LPDDR5/LPDDR5_A.CA3")
			(pinfunction "R2.2")
			(pintype "passive")
		)
		(pad "8" smd roundrect
			(at -0.8875 -0.45)
			(size 0.525 0.5)
			(layers "F.Cu" "F.Mask" "F.Paste")
			(roundrect_rratio 0.25)
			(net 59 "/LPDDR5/LPDDR5_A.CA2")
			(pinfunction "R1.2")
			(pintype "passive")
		)
	)
	(footprint "antmicro-footprints:R_0402_1005Metric"
		(layer "F.Cu")
		(at 117.625 93.8 90)
		(descr "Resistor SMD 0402")
		(tags "resistor SMD 0402")
		(property "Reference" "R93"
			(at -3.1 0.375 90)
			(unlocked yes)
			(layer "F.SilkS")
			(effects
				(font
					(size 0.7 0.7)
					(thickness 0.15)
				)
				(justify left bottom)
			)
		)
		(property "Value" "R_100R_0402"
			(at -1.011843 1.772047 90)
			(layer "F.Fab")
			(effects
				(font
					(size 0.7 0.7)
					(thickness 0.15)
				)
				(justify left bottom)
			)
		)
		(property "Author" "Antmicro"
			(at 211.425 -23.825 0)
			(layer "F.Fab")
			(hide yes)
			(effects
				(font
					(size 1 1)
					(thickness 0.15)
				)
			)
		)
		(property "License" "Apache-2.0"
			(at 211.425 -23.825 0)
			(layer "F.Fab")
			(hide yes)
			(effects
				(font
					(size 1 1)
					(thickness 0.15)
				)
			)
		)
		(property "MPN" "CR0402-FX-1000GLF"
			(at 211.425 -23.825 0)
			(layer "F.Fab")
			(hide yes)
			(effects
				(font
					(size 1 1)
					(thickness 0.15)
				)
			)
		)
		(property "Manufacturer" "Bourns"
			(at 211.425 -23.825 0)
			(layer "F.Fab")
			(hide yes)
			(effects
				(font
					(size 1 1)
					(thickness 0.15)
				)
			)
		)
		(property "Tolerance" "1%"
			(at 211.425 -23.825 0)
			(layer "F.Fab")
			(hide yes)
			(effects
				(font
					(size 1 1)
					(thickness 0.15)
				)
			)
		)
		(property "Val" "100R"
			(at 211.425 -23.825 0)
			(layer "F.Fab")
			(hide yes)
			(effects
				(font
					(size 1 1)
					(thickness 0.15)
				)
			)
		)
		(sheetname "Translators")
		(sheetfile "translators.kicad_sch")
		(attr smd)
		(fp_rect
			(start -0.93 -0.47)
			(end 0.93 0.47)
			(stroke
				(width 0.05)
				(type solid)
			)
			(fill no)
			(layer "F.CrtYd")
		)
		(fp_rect
			(start -0.5 -0.25)
			(end 0.5 0.25)
			(stroke
				(width 0.15)
				(type solid)
			)
			(fill no)
			(layer "F.Fab")
		)
		(pad "1" smd roundrect
			(at -0.485 0 90)
			(size 0.59 0.64)
			(layers "F.Cu" "F.Mask" "F.Paste")
			(roundrect_rratio 0.25)
			(net 119 "/SODIMM/LPDDR5_IN_A.DMI0")
			(pintype "passive")
		)
		(pad "2" smd roundrect
			(at 0.485 0 90)
			(size 0.59 0.64)
			(layers "F.Cu" "F.Mask" "F.Paste")
			(roundrect_rratio 0.25)
			(net 201 "/LPDDR5/LPDDR5_A.DMI0")
			(pintype "passive")
		)
	)
)
